(kicad_pcb
	(version 20260206)
	(generator "pcbnew")
	(generator_version "10.0")
	(general
		(thickness 1.6)
		(legacy_teardrops no)
	)
	(paper "A4")
	(title_block
		(title "baseboard — 13948-1b.1110WZS1818.brd")
		(comment 1 "Honey Badger (Wiwynn) / footprints 1652-1660 of 2523")
	)
	(layers
		(0 "F.Cu" signal "TOP")
		(4 "In1.Cu" signal "L2GND")
		(6 "In2.Cu" signal "L3")
		(8 "In3.Cu" signal "L4VCC")
		(10 "In4.Cu" signal "L5VCC")
		(12 "In5.Cu" signal "L6")
		(14 "In6.Cu" signal "L7GND")
		(2 "B.Cu" signal "BOTTOM")
		(9 "F.Adhes" user "F.Adhesive")
		(11 "B.Adhes" user "B.Adhesive")
		(13 "F.Paste" user "Package Geometry/Pastemask Top")
		(15 "B.Paste" user "Package Geometry/Pastemask Bottom")
		(5 "F.SilkS" user "Ref Des/Silkscreen Top")
		(7 "B.SilkS" user "Ref Des/Silkscreen Bottom")
		(1 "F.Mask" user "Board Geometry/Soldermask Top")
		(3 "B.Mask" user "Board Geometry/Soldermask Bottom")
		(17 "Dwgs.User" user "User.Drawings")
		(19 "Cmts.User" user "User.Comments")
		(21 "Eco1.User" user "User.Eco1")
		(23 "Eco2.User" user "User.Eco2")
		(25 "Edge.Cuts" user "Board Geometry/Outline")
		(27 "Margin" user)
		(31 "F.CrtYd" user "Package Geometry/Place Bound Top")
		(29 "B.CrtYd" user "Package Geometry/Place Bound Bottom")
		(35 "F.Fab" user "Ref Des/Assembly Top")
		(33 "B.Fab" user "Ref Des/Assembly Bottom")
	)
	(footprint ""
		(layer "F.Cu")
		(at 35.383216 -204.14488 90)
		(property "Reference" "R5311"
			(at 0 0 90)
			(layer "F.SilkS")
			(hide yes)
			(effects
				(font
					(size 1.27 1.27)
				)
			)
		)
		(property "Value" "0R2J-2-GP"
			(at 0.064008 -3.993896 90)
			(unlocked yes)
			(layer "F.Fab")
			(hide yes)
			(effects
				(font
					(size 1.016 1.016)
					(thickness 0.1524)
				)
			)
		)
		(property "Device Type" "R402H16"
			(at 0.064008 -5.517896 90)
			(unlocked yes)
			(layer "F.Fab")
			(hide yes)
			(effects
				(font
					(size 1.016 1.016)
					(thickness 0.1524)
				)
			)
		)
		(duplicate_pad_numbers_are_jumpers no)
		(fp_line
			(start 0.508 -0.9398)
			(end -0.508 -0.9398)
			(stroke
				(width 0.1524)
				(type default)
			)
			(layer "F.SilkS")
		)
		(fp_line
			(start -0.508 -0.9398)
			(end -0.508 0.9398)
			(stroke
				(width 0.1524)
				(type default)
			)
			(layer "F.SilkS")
		)
		(fp_rect
			(start -0.508 0.9398)
			(end 0.508 -0.9398)
			(stroke
				(width 0)
				(type default)
			)
			(fill no)
			(layer "F.CrtYd")
		)
		(fp_rect
			(start -0.508 0.9398)
			(end 0.508 -0.9398)
			(stroke
				(width 0)
				(type default)
			)
			(fill no)
			(layer "F.Fab")
		)
		(pad "1" smd custom
			(at 0 -0.4445 90)
			(size 0.1397 0.1397)
			(layers "F.Cu" "F.Mask" "F.Paste")
			(net "VOL_SEN_SDA_U17")
			(options
				(clearance outline)
				(anchor circle)
			)
			(primitives
				(gr_poly
					(pts
						(arc
							(start -0.1778 -0.2794)
							(mid -0.249642 -0.249642)
							(end -0.2794 -0.1778)
						)
						(arc
							(start -0.2794 0.1778)
							(mid -0.249642 0.249642)
							(end -0.1778 0.2794)
						)
						(arc
							(start 0.1778 0.2794)
							(mid 0.249642 0.249642)
							(end 0.2794 0.1778)
						)
						(arc
							(start 0.2794 -0.1778)
							(mid 0.249642 -0.249642)
							(end 0.1778 -0.2794)
						)
					)
					(width 0)
					(fill yes)
				)
			)
		)
		(pad "2" smd custom
			(at 0 0.4445 90)
			(size 0.1397 0.1397)
			(layers "F.Cu" "F.Mask" "F.Paste")
			(net "BMC_I2C_SDA_10")
			(options
				(clearance outline)
				(anchor circle)
			)
			(primitives
				(gr_poly
					(pts
						(arc
							(start -0.1778 -0.2794)
							(mid -0.249642 -0.249642)
							(end -0.2794 -0.1778)
						)
						(arc
							(start -0.2794 0.1778)
							(mid -0.249642 0.249642)
							(end -0.1778 0.2794)
						)
						(arc
							(start 0.1778 0.2794)
							(mid 0.249642 0.249642)
							(end 0.2794 0.1778)
						)
						(arc
							(start 0.2794 -0.1778)
							(mid 0.249642 -0.249642)
							(end 0.1778 -0.2794)
						)
					)
					(width 0)
					(fill yes)
				)
			)
		)
	)
	(footprint ""
		(layer "F.Cu")
		(at 68.834 -45.847 -90)
		(property "Reference" "SC936"
			(at 0 0 270)
			(layer "F.SilkS")
			(hide yes)
			(effects
				(font
					(size 1.27 1.27)
				)
			)
		)
		(property "Value" "SC10U6D3V5KX-4GP"
			(at -0.0762 -6.1214 270)
			(unlocked yes)
			(layer "F.Fab")
			(hide yes)
			(effects
				(font
					(size 1.016 1.016)
					(thickness 0.1524)
				)
			)
		)
		(property "Device Type" "C805H58"
			(at -0.0762 -8.1534 270)
			(unlocked yes)
			(layer "F.Fab")
			(hide yes)
			(effects
				(font
					(size 1.016 1.016)
					(thickness 0.1524)
				)
			)
		)
		(duplicate_pad_numbers_are_jumpers no)
		(fp_line
			(start 0.635 0)
			(end -0.635 0)
			(stroke
				(width 0.508)
				(type default)
			)
			(layer "F.SilkS")
		)
		(fp_rect
			(start -0.9652 1.778)
			(end 0.9652 -1.778)
			(stroke
				(width 0)
				(type default)
			)
			(fill no)
			(layer "F.CrtYd")
		)
		(fp_poly
			(pts
				(xy -0.9652 -1.778) (xy 0.9652 -1.778) (xy 0.9652 1.778) (xy -0.9652 1.778)
			)
			(stroke
				(width 0)
				(type default)
			)
			(fill no)
			(layer "F.Fab")
		)
		(pad "1" smd rect
			(at 0 -0.9652 270)
			(size 1.397 1.143)
			(layers "F.Cu" "F.Mask" "F.Paste")
			(net "SAS0_VDDH")
		)
		(pad "2" smd rect
			(at 0 0.9652 270)
			(size 1.397 1.143)
			(layers "F.Cu" "F.Mask" "F.Paste")
			(net "GND")
		)
	)
	(footprint ""
		(layer "F.Cu")
		(at 261.562596 -50.692812 90)
		(property "Reference" "SR719"
			(at 0 0 90)
			(layer "F.SilkS")
			(hide yes)
			(effects
				(font
					(size 1.27 1.27)
				)
			)
		)
		(property "Value" "4K7R2F-GP"
			(at 0.064008 -3.993896 90)
			(unlocked yes)
			(layer "F.Fab")
			(hide yes)
			(effects
				(font
					(size 1.016 1.016)
					(thickness 0.1524)
				)
			)
		)
		(property "Device Type" "R402H16"
			(at 0.064008 -5.517896 90)
			(unlocked yes)
			(layer "F.Fab")
			(hide yes)
			(effects
				(font
					(size 1.016 1.016)
					(thickness 0.1524)
				)
			)
		)
		(duplicate_pad_numbers_are_jumpers no)
		(fp_line
			(start 0.508 -0.9398)
			(end -0.508 -0.9398)
			(stroke
				(width 0.1524)
				(type default)
			)
			(layer "F.SilkS")
		)
		(fp_line
			(start -0.508 -0.9398)
			(end -0.508 0.9398)
			(stroke
				(width 0.1524)
				(type default)
			)
			(layer "F.SilkS")
		)
		(fp_rect
			(start -0.508 0.9398)
			(end 0.508 -0.9398)
			(stroke
				(width 0)
				(type default)
			)
			(fill no)
			(layer "F.CrtYd")
		)
		(fp_rect
			(start -0.508 0.9398)
			(end 0.508 -0.9398)
			(stroke
				(width 0)
				(type default)
			)
			(fill no)
			(layer "F.Fab")
		)
		(pad "1" smd custom
			(at 0 -0.4445 90)
			(size 0.1397 0.1397)
			(layers "F.Cu" "F.Mask" "F.Paste")
			(net "IOC_EEPROM_A0")
			(options
				(clearance outline)
				(anchor circle)
			)
			(primitives
				(gr_poly
					(pts
						(arc
							(start -0.1778 -0.2794)
							(mid -0.249642 -0.249642)
							(end -0.2794 -0.1778)
						)
						(arc
							(start -0.2794 0.1778)
							(mid -0.249642 0.249642)
							(end -0.1778 0.2794)
						)
						(arc
							(start 0.1778 0.2794)
							(mid 0.249642 0.249642)
							(end 0.2794 0.1778)
						)
						(arc
							(start 0.2794 -0.1778)
							(mid 0.249642 -0.249642)
							(end 0.1778 -0.2794)
						)
					)
					(width 0)
					(fill yes)
				)
			)
		)
		(pad "2" smd custom
			(at 0 0.4445 90)
			(size 0.1397 0.1397)
			(layers "F.Cu" "F.Mask" "F.Paste")
			(net "GND")
			(options
				(clearance outline)
				(anchor circle)
			)
			(primitives
				(gr_poly
					(pts
						(arc
							(start -0.1778 -0.2794)
							(mid -0.249642 -0.249642)
							(end -0.2794 -0.1778)
						)
						(arc
							(start -0.2794 0.1778)
							(mid -0.249642 0.249642)
							(end -0.1778 0.2794)
						)
						(arc
							(start 0.1778 0.2794)
							(mid 0.249642 0.249642)
							(end 0.2794 0.1778)
						)
						(arc
							(start 0.2794 -0.1778)
							(mid 0.249642 -0.249642)
							(end 0.1778 -0.2794)
						)
					)
					(width 0)
					(fill yes)
				)
			)
		)
	)
	(footprint ""
		(layer "F.Cu")
		(at 96.120966 -61.468)
		(property "Reference" "STP33"
			(at 0 0 0)
			(layer "F.SilkS")
			(hide yes)
			(effects
				(font
					(size 1.27 1.27)
				)
			)
		)
		(property "Value" "TPAD28"
			(at 0.0127 -1.8034 0)
			(unlocked yes)
			(layer "F.Fab")
			(hide yes)
			(effects
				(font
					(size 1.016 1.016)
					(thickness 0.1524)
				)
			)
		)
		(property "Device Type" "TPAD28"
			(at 0.0127 -3.3274 0)
			(unlocked yes)
			(layer "F.Fab")
			(hide yes)
			(effects
				(font
					(size 1.016 1.016)
					(thickness 0.1524)
				)
			)
		)
		(duplicate_pad_numbers_are_jumpers no)
		(fp_poly
			(pts
				(arc
					(start 0.3556 0)
					(mid -0.3556 0)
					(end 0.3556 0)
				)
			)
			(stroke
				(width 0)
				(type default)
			)
			(fill no)
			(layer "F.CrtYd")
		)
		(fp_poly
			(pts
				(arc
					(start 0.6096 0)
					(mid -0.6096 0)
					(end 0.6096 0)
				)
			)
			(stroke
				(width 0)
				(type default)
			)
			(fill no)
			(layer "F.Fab")
		)
		(pad "1" smd circle
			(at 0 0)
			(size 0.7112 0.7112)
			(layers "F.Cu" "F.Mask" "F.Paste")
			(net "ICE0_TDO")
		)
	)
	(footprint ""
		(layer "F.Cu")
		(at 172.675804 -26.295096 90)
		(property "Reference" "R389"
			(at 0 0 90)
			(layer "F.SilkS")
			(hide yes)
			(effects
				(font
					(size 1.27 1.27)
				)
			)
		)
		(property "Value" "0R2J-2-GP"
			(at 0.064008 -3.993896 90)
			(unlocked yes)
			(layer "F.Fab")
			(hide yes)
			(effects
				(font
					(size 1.016 1.016)
					(thickness 0.1524)
				)
			)
		)
		(property "Device Type" "R402H16"
			(at 0.064008 -5.517896 90)
			(unlocked yes)
			(layer "F.Fab")
			(hide yes)
			(effects
				(font
					(size 1.016 1.016)
					(thickness 0.1524)
				)
			)
		)
		(duplicate_pad_numbers_are_jumpers no)
		(fp_line
			(start 0.508 -0.9398)
			(end -0.508 -0.9398)
			(stroke
				(width 0.1524)
				(type default)
			)
			(layer "F.SilkS")
		)
		(fp_line
			(start -0.508 -0.9398)
			(end -0.508 0.9398)
			(stroke
				(width 0.1524)
				(type default)
			)
			(layer "F.SilkS")
		)
		(fp_rect
			(start -0.508 0.9398)
			(end 0.508 -0.9398)
			(stroke
				(width 0)
				(type default)
			)
			(fill no)
			(layer "F.CrtYd")
		)
		(fp_rect
			(start -0.508 0.9398)
			(end 0.508 -0.9398)
			(stroke
				(width 0)
				(type default)
			)
			(fill no)
			(layer "F.Fab")
		)
		(pad "1" smd custom
			(at 0 -0.4445 90)
			(size 0.1397 0.1397)
			(layers "F.Cu" "F.Mask" "F.Paste")
			(net "BCM5221_MB_TX_DN")
			(options
				(clearance outline)
				(anchor circle)
			)
			(primitives
				(gr_poly
					(pts
						(arc
							(start -0.1778 -0.2794)
							(mid -0.249642 -0.249642)
							(end -0.2794 -0.1778)
						)
						(arc
							(start -0.2794 0.1778)
							(mid -0.249642 0.249642)
							(end -0.1778 0.2794)
						)
						(arc
							(start 0.1778 0.2794)
							(mid 0.249642 0.249642)
							(end 0.2794 0.1778)
						)
						(arc
							(start 0.2794 -0.1778)
							(mid 0.249642 -0.249642)
							(end 0.1778 -0.2794)
						)
					)
					(width 0)
					(fill yes)
				)
			)
		)
		(pad "2" smd custom
			(at 0 0.4445 90)
			(size 0.1397 0.1397)
			(layers "F.Cu" "F.Mask" "F.Paste")
			(net "BCM5221_TX_C_DN")
			(options
				(clearance outline)
				(anchor circle)
			)
			(primitives
				(gr_poly
					(pts
						(arc
							(start -0.1778 -0.2794)
							(mid -0.249642 -0.249642)
							(end -0.2794 -0.1778)
						)
						(arc
							(start -0.2794 0.1778)
							(mid -0.249642 0.249642)
							(end -0.1778 0.2794)
						)
						(arc
							(start 0.1778 0.2794)
							(mid 0.249642 0.249642)
							(end 0.2794 0.1778)
						)
						(arc
							(start 0.2794 -0.1778)
							(mid 0.249642 -0.249642)
							(end 0.1778 -0.2794)
						)
					)
					(width 0)
					(fill yes)
				)
			)
		)
	)
	(footprint ""
		(layer "F.Cu")
		(at 111.252 -76.327)
		(property "Reference" "STP65"
			(at 0 0 0)
			(layer "F.SilkS")
			(hide yes)
			(effects
				(font
					(size 1.27 1.27)
				)
			)
		)
		(property "Value" "TPAD28"
			(at 0.0127 -1.8034 0)
			(unlocked yes)
			(layer "F.Fab")
			(hide yes)
			(effects
				(font
					(size 1.016 1.016)
					(thickness 0.1524)
				)
			)
		)
		(property "Device Type" "TPAD28"
			(at 0.0127 -3.3274 0)
			(unlocked yes)
			(layer "F.Fab")
			(hide yes)
			(effects
				(font
					(size 1.016 1.016)
					(thickness 0.1524)
				)
			)
		)
		(duplicate_pad_numbers_are_jumpers no)
		(fp_poly
			(pts
				(arc
					(start 0.3556 0)
					(mid -0.3556 0)
					(end 0.3556 0)
				)
			)
			(stroke
				(width 0)
				(type default)
			)
			(fill no)
			(layer "F.CrtYd")
		)
		(fp_poly
			(pts
				(arc
					(start 0.6096 0)
					(mid -0.6096 0)
					(end 0.6096 0)
				)
			)
			(stroke
				(width 0)
				(type default)
			)
			(fill no)
			(layer "F.Fab")
		)
		(pad "1" smd circle
			(at 0 0)
			(size 0.7112 0.7112)
			(layers "F.Cu" "F.Mask" "F.Paste")
			(net "EXP_TEST_MUX27")
		)
	)
	(footprint ""
		(layer "F.Cu")
		(at 182.38597 -67.183)
		(property "Reference" "C291"
			(at 0 0 0)
			(layer "F.SilkS")
			(hide yes)
			(effects
				(font
					(size 1.27 1.27)
				)
			)
		)
		(property "Value" "SCD1U25V2KX-2-GP"
			(at 1.1811 -2.7051 0)
			(unlocked yes)
			(layer "F.Fab")
			(hide yes)
			(effects
				(font
					(size 1.016 1.016)
					(thickness 0.1524)
				)
			)
		)
		(property "Device Type" "C402H22"
			(at 1.1811 -4.2291 0)
			(unlocked yes)
			(layer "F.Fab")
			(hide yes)
			(effects
				(font
					(size 1.016 1.016)
					(thickness 0.1524)
				)
			)
		)
		(duplicate_pad_numbers_are_jumpers no)
		(fp_rect
			(start -0.4318 0.9525)
			(end 0.4318 -0.9525)
			(stroke
				(width 0)
				(type default)
			)
			(fill no)
			(layer "F.CrtYd")
		)
		(fp_rect
			(start -0.4318 0.9525)
			(end 0.4318 -0.9525)
			(stroke
				(width 0)
				(type default)
			)
			(fill no)
			(layer "F.Fab")
		)
		(pad "1" smd custom
			(at 0 -0.4445)
			(size 0.1524 0.1524)
			(layers "F.Cu" "F.Mask" "F.Paste")
			(net "TP_MSB_A34_CPU_SATA_RX_N")
			(options
				(clearance outline)
				(anchor circle)
			)
			(primitives
				(gr_poly
					(pts
						(arc
							(start 0.3048 -0.2032)
							(mid 0.275042 -0.275042)
							(end 0.2032 -0.3048)
						)
						(arc
							(start -0.2032 -0.3048)
							(mid -0.275042 -0.275042)
							(end -0.3048 -0.2032)
						)
						(arc
							(start -0.3048 0.2032)
							(mid -0.275042 0.275042)
							(end -0.2032 0.3048)
						)
						(arc
							(start 0.2032 0.3048)
							(mid 0.275042 0.275042)
							(end 0.3048 0.2032)
						)
					)
					(width 0)
					(fill yes)
				)
			)
		)
		(pad "2" smd custom
			(at 0 0.4445)
			(size 0.1524 0.1524)
			(layers "F.Cu" "F.Mask" "F.Paste")
			(net "GND")
			(options
				(clearance outline)
				(anchor circle)
			)
			(primitives
				(gr_poly
					(pts
						(arc
							(start 0.3048 -0.2032)
							(mid 0.275042 -0.275042)
							(end 0.2032 -0.3048)
						)
						(arc
							(start -0.2032 -0.3048)
							(mid -0.275042 -0.275042)
							(end -0.3048 -0.2032)
						)
						(arc
							(start -0.3048 0.2032)
							(mid -0.275042 0.275042)
							(end -0.2032 0.3048)
						)
						(arc
							(start 0.2032 0.3048)
							(mid 0.275042 0.275042)
							(end 0.3048 0.2032)
						)
					)
					(width 0)
					(fill yes)
				)
			)
		)
	)
	(footprint ""
		(layer "F.Cu")
		(at 185.792872 -198.496936 180)
		(property "Reference" "C244"
			(at 0 0 180)
			(layer "F.SilkS")
			(hide yes)
			(effects
				(font
					(size 1.27 1.27)
				)
			)
		)
		(property "Value" "SCD01U50V2KX-1GP"
			(at 1.1811 -2.7051 180)
			(unlocked yes)
			(layer "F.Fab")
			(hide yes)
			(effects
				(font
					(size 1.016 1.016)
					(thickness 0.1524)
				)
			)
		)
		(property "Device Type" "C402H22"
			(at 1.1811 -4.2291 180)
			(unlocked yes)
			(layer "F.Fab")
			(hide yes)
			(effects
				(font
					(size 1.016 1.016)
					(thickness 0.1524)
				)
			)
		)
		(duplicate_pad_numbers_are_jumpers no)
		(fp_rect
			(start -0.4318 0.9525)
			(end 0.4318 -0.9525)
			(stroke
				(width 0)
				(type default)
			)
			(fill no)
			(layer "F.CrtYd")
		)
		(fp_rect
			(start -0.4318 0.9525)
			(end 0.4318 -0.9525)
			(stroke
				(width 0)
				(type default)
			)
			(fill no)
			(layer "F.Fab")
		)
		(pad "1" smd custom
			(at 0 -0.4445 180)
			(size 0.1524 0.1524)
			(layers "F.Cu" "F.Mask" "F.Paste")
			(net "P3V3_STBY")
			(options
				(clearance outline)
				(anchor circle)
			)
			(primitives
				(gr_poly
					(pts
						(arc
							(start 0.3048 -0.2032)
							(mid 0.275042 -0.275042)
							(end 0.2032 -0.3048)
						)
						(arc
							(start -0.2032 -0.3048)
							(mid -0.275042 -0.275042)
							(end -0.3048 -0.2032)
						)
						(arc
							(start -0.3048 0.2032)
							(mid -0.275042 0.275042)
							(end -0.2032 0.3048)
						)
						(arc
							(start 0.2032 0.3048)
							(mid 0.275042 0.275042)
							(end 0.3048 0.2032)
						)
					)
					(width 0)
					(fill yes)
				)
			)
		)
		(pad "2" smd custom
			(at 0 0.4445 180)
			(size 0.1524 0.1524)
			(layers "F.Cu" "F.Mask" "F.Paste")
			(net "GND")
			(options
				(clearance outline)
				(anchor circle)
			)
			(primitives
				(gr_poly
					(pts
						(arc
							(start 0.3048 -0.2032)
							(mid 0.275042 -0.275042)
							(end 0.2032 -0.3048)
						)
						(arc
							(start -0.2032 -0.3048)
							(mid -0.275042 -0.275042)
							(end -0.3048 -0.2032)
						)
						(arc
							(start -0.3048 0.2032)
							(mid -0.275042 0.275042)
							(end -0.2032 0.3048)
						)
						(arc
							(start 0.2032 0.3048)
							(mid 0.275042 0.275042)
							(end 0.3048 0.2032)
						)
					)
					(width 0)
					(fill yes)
				)
			)
		)
	)
	(footprint ""
		(layer "F.Cu")
		(at 222.377 -118.745 -90)
		(property "Reference" "PR178"
			(at 0 0 270)
			(layer "F.SilkS")
			(hide yes)
			(effects
				(font
					(size 1.27 1.27)
				)
			)
		)
		(property "Value" "0R2J-2-GP"
			(at 0.064008 -3.993896 270)
			(unlocked yes)
			(layer "F.Fab")
			(hide yes)
			(effects
				(font
					(size 1.016 1.016)
					(thickness 0.1524)
				)
			)
		)
		(property "Device Type" "R402H16"
			(at 0.064008 -5.517896 270)
			(unlocked yes)
			(layer "F.Fab")
			(hide yes)
			(effects
				(font
					(size 1.016 1.016)
					(thickness 0.1524)
				)
			)
		)
		(duplicate_pad_numbers_are_jumpers no)
		(fp_line
			(start -0.508 -0.9398)
			(end -0.508 0.9398)
			(stroke
				(width 0.1524)
				(type default)
			)
			(layer "F.SilkS")
		)
		(fp_line
			(start 0.508 -0.9398)
			(end -0.508 -0.9398)
			(stroke
				(width 0.1524)
				(type default)
			)
			(layer "F.SilkS")
		)
		(fp_rect
			(start -0.508 0.9398)
			(end 0.508 -0.9398)
			(stroke
				(width 0)
				(type default)
			)
			(fill no)
			(layer "F.CrtYd")
		)
		(fp_rect
			(start -0.508 0.9398)
			(end 0.508 -0.9398)
			(stroke
				(width 0)
				(type default)
			)
			(fill no)
			(layer "F.Fab")
		)
		(pad "1" smd custom
			(at 0 -0.4445 270)
			(size 0.1397 0.1397)
			(layers "F.Cu" "F.Mask" "F.Paste")
			(net "P3V3_STBY_B3")
			(options
				(clearance outline)
				(anchor circle)
			)
			(primitives
				(gr_poly
					(pts
						(arc
							(start -0.1778 -0.2794)
							(mid -0.249642 -0.249642)
							(end -0.2794 -0.1778)
						)
						(arc
							(start -0.2794 0.1778)
							(mid -0.249642 0.249642)
							(end -0.1778 0.2794)
						)
						(arc
							(start 0.1778 0.2794)
							(mid 0.249642 0.249642)
							(end 0.2794 0.1778)
						)
						(arc
							(start 0.2794 -0.1778)
							(mid 0.249642 -0.249642)
							(end 0.1778 -0.2794)
						)
					)
					(width 0)
					(fill yes)
				)
			)
		)
		(pad "2" smd custom
			(at 0 0.4445 270)
			(size 0.1397 0.1397)
			(layers "F.Cu" "F.Mask" "F.Paste")
			(net "P3V3_STBY_R3")
			(options
				(clearance outline)
				(anchor circle)
			)
			(primitives
				(gr_poly
					(pts
						(arc
							(start -0.1778 -0.2794)
							(mid -0.249642 -0.249642)
							(end -0.2794 -0.1778)
						)
						(arc
							(start -0.2794 0.1778)
							(mid -0.249642 0.249642)
							(end -0.1778 0.2794)
						)
						(arc
							(start 0.1778 0.2794)
							(mid 0.249642 0.249642)
							(end 0.2794 0.1778)
						)
						(arc
							(start 0.2794 -0.1778)
							(mid 0.249642 -0.249642)
							(end 0.1778 -0.2794)
						)
					)
					(width 0)
					(fill yes)
				)
			)
		)
	)
)
